# S9S_MB_2U (Grand Teton) — schematic netlist excerpt (pin names and nets, part order shuffled) for the footprints in the layout excerpt that follows; sources: Cadence DE-HDL packaged netlist, KiCad conversion of 03242023_DA0F0TMBIJ0_F0T_Motherboard_J_brd_V01_OCP.brd

U313  GL852GOHY60  GL852G-OHY60 EMPTY  pkg QFN28_THXL  page 196
  DM0  = USB2_PCH_0_R_DN
  DP0  = USB2_PCH_0_R_DP
  DM1  = USB2_HUB_2_EXT_DN
  DP1  = USB2_HUB_2_EXT_DP
  AVDD(0)  = P3V3_AUX_USB_HUB_2
  DM2  = NC_USB_HUB_2_DM2
  DP2  = NC_USB_HUB_2_DP2
  RREF  = USB_HUB_2_RREF
  AVDD(1)  = P3V3_AUX_USB_HUB_2
  X1  = USB_HUB_2_XTAL_IN
  X2  = USB_HUB_2_XTAL_OUT
  DM3  = NC_USB_HUB_2_DM3
  DP3  = NC_USB_HUB_2_DP3
  AVDD(2)  = P3V3_AUX_USB_HUB_2
  DM4  = NC_USB_HUB_2_DM4
  DP4  = NC_USB_HUB_2_DP4
  \reset#\  = RST_USB_HUB_2_R_N
  \test||scl\  = USB_HUB_2_TEST
  \ovcur4#\  = USB_HUB_2_OVCUR4
  \ovcur3#\  = USB_HUB_2_OVCUR3
  DVDD  = USB_HUB_2_DVDD
  PSELF  = USB_HUB_2_PSELF
  PGANG  = USB_HUB_2_PGANG
  \ovcur2#||smd\  = USB_HUB_2_OVCUR2
  \ovcur1#||smc\  = USB_HUB_2_OVCUR1
  SDA  = NC_USB_HUB_2_SDA
  V5  = P3V3_AUX_USB_HUB_2
  V33  = P3V3_AUX_USB_HUB_2
  TH  = GND

(kicad_pcb
	(version 20260206)
	(generator "pcbnew")
	(generator_version "10.0")
	(general
		(thickness 1.6)
		(legacy_teardrops no)
	)
	(paper "A4")
	(title_block
		(title "03242023_DA0F0TMBIJ0_F0T_Motherboard_J_brd_V01_OCP.brd")
		(comment 1 "Grand Teton / footprint 1287 of 6105 (U313), pads 1-29 of 29")
	)
	(layers
		(0 "F.Cu" signal "TOP")
		(4 "In1.Cu" signal "GND")
		(6 "In2.Cu" signal "IN1")
		(8 "In3.Cu" signal "GND1")
		(10 "In4.Cu" signal "IN2")
		(12 "In5.Cu" signal "GND2")
		(14 "In6.Cu" signal "IN3")
		(16 "In7.Cu" signal "GND3")
		(18 "In8.Cu" signal "VCC")
		(20 "In9.Cu" signal "VCC1")
		(22 "In10.Cu" signal "GND4")
		(24 "In11.Cu" signal "IN4")
		(26 "In12.Cu" signal "GND5")
		(28 "In13.Cu" signal "IN5")
		(30 "In14.Cu" signal "GND6")
		(32 "In15.Cu" signal "IN6")
		(34 "In16.Cu" signal "GND7")
		(2 "B.Cu" signal "BOTTOM")
		(9 "F.Adhes" user "F.Adhesive")
		(11 "B.Adhes" user "B.Adhesive")
		(13 "F.Paste" user "Package Geometry/Pastemask Top")
		(15 "B.Paste" user "Package Geometry/Pastemask Bottom")
		(5 "F.SilkS" user "Ref Des/Silkscreen Top")
		(7 "B.SilkS" user "Ref Des/Silkscreen Bottom")
		(1 "F.Mask" user "Board Geometry/Soldermask Top")
		(3 "B.Mask" user "Board Geometry/Soldermask Bottom")
		(17 "Dwgs.User" user "User.Drawings")
		(19 "Cmts.User" user "User.Comments")
		(21 "Eco1.User" user "User.Eco1")
		(23 "Eco2.User" user "User.Eco2")
		(25 "Edge.Cuts" user "Board Geometry/Outline")
		(27 "Margin" user)
		(31 "F.CrtYd" user "Package Geometry/Place Bound Top")
		(29 "B.CrtYd" user "Package Geometry/Place Bound Bottom")
		(35 "F.Fab" user "Ref Des/Assembly Top")
		(33 "B.Fab" user "Ref Des/Assembly Bottom")
	)
	(footprint ""
		(layer "F.Cu")
		(at 157.135576 -37.790374 -90)
		(property "Reference" "U313"
			(at -3.6957 -3.129534 0)
			(unlocked yes)
			(layer "F.SilkS")
			(effects
				(font
					(size 0.7874 0.5842)
					(thickness 0.1524)
				)
				(justify left)
			)
		)
		(property "Value" ""
			(at 0 0 270)
			(layer "F.Fab")
			(effects
				(font
					(size 1.27 1.27)
				)
			)
		)
		(duplicate_pad_numbers_are_jumpers no)
		(pad "1" smd rect
			(at -2.412492 -1.500124)
			(size 0.254 0.7366)
			(layers "F.Cu" "F.Mask" "F.Paste")
			(net "USB2_PCH_0_R_DN")
		)
		(pad "2" smd rect
			(at -2.412492 -0.999998)
			(size 0.254 0.7366)
			(layers "F.Cu" "F.Mask" "F.Paste")
			(net "USB2_PCH_0_R_DP")
		)
		(pad "3" smd rect
			(at -2.412492 -0.499872)
			(size 0.254 0.7366)
			(layers "F.Cu" "F.Mask" "F.Paste")
			(net "USB2_HUB_2_EXT_DN")
		)
		(pad "4" smd rect
			(at -2.412492 0)
			(size 0.254 0.7366)
			(layers "F.Cu" "F.Mask" "F.Paste")
			(net "USB2_HUB_2_EXT_DP")
		)
		(pad "5" smd rect
			(at -2.412492 0.499872)
			(size 0.254 0.7366)
			(layers "F.Cu" "F.Mask" "F.Paste")
			(net "P3V3_AUX_USB_HUB_2")
		)
		(pad "6" smd rect
			(at -2.412492 0.999998)
			(size 0.254 0.7366)
			(layers "F.Cu" "F.Mask" "F.Paste")
			(net "NC_USB_HUB_2_DM2")
		)
		(pad "7" smd rect
			(at -2.412492 1.500124)
			(size 0.254 0.7366)
			(layers "F.Cu" "F.Mask" "F.Paste")
			(net "NC_USB_HUB_2_DP2")
		)
		(pad "8" smd rect
			(at -1.500124 2.412492 270)
			(size 0.254 0.7366)
			(layers "F.Cu" "F.Mask" "F.Paste")
			(net "USB_HUB_2_RREF")
		)
		(pad "9" smd rect
			(at -0.999998 2.412492 270)
			(size 0.254 0.7366)
			(layers "F.Cu" "F.Mask" "F.Paste")
			(net "P3V3_AUX_USB_HUB_2")
		)
		(pad "10" smd rect
			(at -0.499872 2.412492 270)
			(size 0.254 0.7366)
			(layers "F.Cu" "F.Mask" "F.Paste")
			(net "USB_HUB_2_XTAL_IN")
		)
		(pad "11" smd rect
			(at 0 2.412492 270)
			(size 0.254 0.7366)
			(layers "F.Cu" "F.Mask" "F.Paste")
			(net "USB_HUB_2_XTAL_OUT")
		)
		(pad "12" smd rect
			(at 0.499872 2.412492 270)
			(size 0.254 0.7366)
			(layers "F.Cu" "F.Mask" "F.Paste")
			(net "NC_USB_HUB_2_DM3")
		)
		(pad "13" smd rect
			(at 0.999998 2.412492 270)
			(size 0.254 0.7366)
			(layers "F.Cu" "F.Mask" "F.Paste")
			(net "NC_USB_HUB_2_DP3")
		)
		(pad "14" smd rect
			(at 1.500124 2.412492 270)
			(size 0.254 0.7366)
			(layers "F.Cu" "F.Mask" "F.Paste")
			(net "P3V3_AUX_USB_HUB_2")
		)
		(pad "15" smd rect
			(at 2.412492 1.500124)
			(size 0.254 0.7366)
			(layers "F.Cu" "F.Mask" "F.Paste")
			(net "NC_USB_HUB_2_DM4")
		)
		(pad "16" smd rect
			(at 2.412492 0.999998)
			(size 0.254 0.7366)
			(layers "F.Cu" "F.Mask" "F.Paste")
			(net "NC_USB_HUB_2_DP4")
		)
		(pad "17" smd rect
			(at 2.412492 0.499872)
			(size 0.254 0.7366)
			(layers "F.Cu" "F.Mask" "F.Paste")
			(net "RST_USB_HUB_2_R_N")
		)
		(pad "18" smd rect
			(at 2.412492 0)
			(size 0.254 0.7366)
			(layers "F.Cu" "F.Mask" "F.Paste")
			(net "USB_HUB_2_TEST")
		)
		(pad "19" smd rect
			(at 2.412492 -0.499872)
			(size 0.254 0.7366)
			(layers "F.Cu" "F.Mask" "F.Paste")
			(net "USB_HUB_2_OVCUR4")
		)
		(pad "20" smd rect
			(at 2.412492 -0.999998)
			(size 0.254 0.7366)
			(layers "F.Cu" "F.Mask" "F.Paste")
			(net "USB_HUB_2_OVCUR3")
		)
		(pad "21" smd rect
			(at 2.412492 -1.500124)
			(size 0.254 0.7366)
			(layers "F.Cu" "F.Mask" "F.Paste")
			(net "USB_HUB_2_DVDD")
		)
		(pad "22" smd rect
			(at 1.500124 -2.412492 270)
			(size 0.254 0.7366)
			(layers "F.Cu" "F.Mask" "F.Paste")
			(net "USB_HUB_2_PSELF")
		)
		(pad "23" smd rect
			(at 0.999998 -2.412492 270)
			(size 0.254 0.7366)
			(layers "F.Cu" "F.Mask" "F.Paste")
			(net "USB_HUB_2_PGANG")
		)
		(pad "24" smd rect
			(at 0.499872 -2.412492 270)
			(size 0.254 0.7366)
			(layers "F.Cu" "F.Mask" "F.Paste")
			(net "USB_HUB_2_OVCUR2")
		)
		(pad "25" smd rect
			(at 0 -2.412492 270)
			(size 0.254 0.7366)
			(layers "F.Cu" "F.Mask" "F.Paste")
			(net "USB_HUB_2_OVCUR1")
		)
		(pad "26" smd rect
			(at -0.499872 -2.412492 270)
			(size 0.254 0.7366)
			(layers "F.Cu" "F.Mask" "F.Paste")
			(net "NC_USB_HUB_2_SDA")
		)
		(pad "27" smd rect
			(at -0.999998 -2.412492 270)
			(size 0.254 0.7366)
			(layers "F.Cu" "F.Mask" "F.Paste")
			(net "P3V3_AUX_USB_HUB_2")
		)
		(pad "28" smd rect
			(at -1.500124 -2.412492 270)
			(size 0.254 0.7366)
			(layers "F.Cu" "F.Mask" "F.Paste")
			(net "P3V3_AUX_USB_HUB_2")
		)
		(pad "TH" smd rect
			(at 0 0 270)
			(size 3.556 3.556)
			(layers "F.Cu" "F.Mask" "F.Paste")
			(net "GND")
		)
	)
)
